(kicad_pcb
	(version 20260206)
	(generator "pcbnew")
	(generator_version "10.0")
	(general
		(thickness 1.6)
		(legacy_teardrops no)
	)
	(paper "A4")
	(title_block
		(title "03242023_DA0F0TMBIJ0_F0T_Motherboard_J_brd_V01_OCP.brd")
		(comment 1 "Grand Teton / footprints 1859-1865 of 6105")
	)
	(layers
		(0 "F.Cu" signal "TOP")
		(4 "In1.Cu" signal "GND")
		(6 "In2.Cu" signal "IN1")
		(8 "In3.Cu" signal "GND1")
		(10 "In4.Cu" signal "IN2")
		(12 "In5.Cu" signal "GND2")
		(14 "In6.Cu" signal "IN3")
		(16 "In7.Cu" signal "GND3")
		(18 "In8.Cu" signal "VCC")
		(20 "In9.Cu" signal "VCC1")
		(22 "In10.Cu" signal "GND4")
		(24 "In11.Cu" signal "IN4")
		(26 "In12.Cu" signal "GND5")
		(28 "In13.Cu" signal "IN5")
		(30 "In14.Cu" signal "GND6")
		(32 "In15.Cu" signal "IN6")
		(34 "In16.Cu" signal "GND7")
		(2 "B.Cu" signal "BOTTOM")
		(9 "F.Adhes" user "F.Adhesive")
		(11 "B.Adhes" user "B.Adhesive")
		(13 "F.Paste" user "Package Geometry/Pastemask Top")
		(15 "B.Paste" user "Package Geometry/Pastemask Bottom")
		(5 "F.SilkS" user "Ref Des/Silkscreen Top")
		(7 "B.SilkS" user "Ref Des/Silkscreen Bottom")
		(1 "F.Mask" user "Board Geometry/Soldermask Top")
		(3 "B.Mask" user "Board Geometry/Soldermask Bottom")
		(17 "Dwgs.User" user "User.Drawings")
		(19 "Cmts.User" user "User.Comments")
		(21 "Eco1.User" user "User.Eco1")
		(23 "Eco2.User" user "User.Eco2")
		(25 "Edge.Cuts" user "Board Geometry/Outline")
		(27 "Margin" user)
		(31 "F.CrtYd" user "Package Geometry/Place Bound Top")
		(29 "B.CrtYd" user "Package Geometry/Place Bound Bottom")
		(35 "F.Fab" user "Ref Des/Assembly Top")
		(33 "B.Fab" user "Ref Des/Assembly Bottom")
	)
	(footprint ""
		(layer "F.Cu")
		(at 15.197582 -408.516836 90)
		(property "Reference" "R2921"
			(at 0 0 90)
			(layer "F.SilkS")
			(hide yes)
			(effects
				(font
					(size 1.27 1.27)
				)
			)
		)
		(property "Value" ""
			(at 0 0 90)
			(layer "F.Fab")
			(effects
				(font
					(size 1.27 1.27)
				)
			)
		)
		(duplicate_pad_numbers_are_jumpers no)
		(fp_line
			(start 0.7874 -0.4064)
			(end 0.7874 0.4064)
			(stroke
				(width 0.1524)
				(type default)
			)
			(layer "F.SilkS")
		)
		(fp_line
			(start -0.7874 -0.4064)
			(end 0.7874 -0.4064)
			(stroke
				(width 0.1524)
				(type default)
			)
			(layer "F.SilkS")
		)
		(fp_line
			(start 0.7874 0.4064)
			(end -0.7874 0.4064)
			(stroke
				(width 0.1524)
				(type default)
			)
			(layer "F.SilkS")
		)
		(fp_line
			(start -0.7874 0.4064)
			(end -0.7874 -0.4064)
			(stroke
				(width 0.1524)
				(type default)
			)
			(layer "F.SilkS")
		)
		(fp_line
			(start -0.12065 -0.305054)
			(end -0.12065 -0.2794)
			(stroke
				(width 0.1)
				(type default)
			)
			(layer "F.Fab")
		)
		(fp_line
			(start -0.67945 -0.305054)
			(end -0.12065 -0.305054)
			(stroke
				(width 0.1)
				(type default)
			)
			(layer "F.Fab")
		)
		(fp_line
			(start 0.67945 -0.3048)
			(end 0.67945 0.3048)
			(stroke
				(width 0.1)
				(type default)
			)
			(layer "F.Fab")
		)
		(fp_line
			(start 0.12065 -0.3048)
			(end 0.67945 -0.3048)
			(stroke
				(width 0.1)
				(type default)
			)
			(layer "F.Fab")
		)
		(fp_line
			(start 0.12065 -0.2794)
			(end 0.12065 -0.3048)
			(stroke
				(width 0.1)
				(type default)
			)
			(layer "F.Fab")
		)
		(fp_line
			(start -0.12065 -0.2794)
			(end 0.12065 -0.2794)
			(stroke
				(width 0.1)
				(type default)
			)
			(layer "F.Fab")
		)
		(fp_line
			(start 0.120396 0.2794)
			(end -0.12065 0.2794)
			(stroke
				(width 0.1)
				(type default)
			)
			(layer "F.Fab")
		)
		(fp_line
			(start -0.12065 0.2794)
			(end -0.12065 0.3048)
			(stroke
				(width 0.1)
				(type default)
			)
			(layer "F.Fab")
		)
		(fp_line
			(start 0.67945 0.3048)
			(end 0.120396 0.3048)
			(stroke
				(width 0.1)
				(type default)
			)
			(layer "F.Fab")
		)
		(fp_line
			(start 0.120396 0.3048)
			(end 0.120396 0.2794)
			(stroke
				(width 0.1)
				(type default)
			)
			(layer "F.Fab")
		)
		(fp_line
			(start -0.12065 0.3048)
			(end -0.67945 0.3048)
			(stroke
				(width 0.1)
				(type default)
			)
			(layer "F.Fab")
		)
		(fp_line
			(start -0.67945 0.3048)
			(end -0.67945 -0.305054)
			(stroke
				(width 0.1)
				(type default)
			)
			(layer "F.Fab")
		)
		(pad "1" smd circle
			(at -0.40005 0 90)
			(size 0 0)
			(layers "F.Cu" "F.Mask" "F.Paste")
			(net "P3V3_AUX")
		)
		(pad "2" smd circle
			(at 0.40005 0 90)
			(size 0 0)
			(layers "F.Cu" "F.Mask" "F.Paste")
			(net "RST_SMB_SWITCH_N")
		)
	)
	(footprint ""
		(layer "F.Cu")
		(at 367.44783 -240.276888 90)
		(property "Reference" "C404"
			(at 0 0 90)
			(layer "F.SilkS")
			(hide yes)
			(effects
				(font
					(size 1.27 1.27)
				)
			)
		)
		(property "Value" ""
			(at 0 0 90)
			(layer "F.Fab")
			(effects
				(font
					(size 1.27 1.27)
				)
			)
		)
		(duplicate_pad_numbers_are_jumpers no)
		(fp_line
			(start 0.7874 -0.4064)
			(end 0.7874 0.4064)
			(stroke
				(width 0.1524)
				(type default)
			)
			(layer "F.SilkS")
		)
		(fp_line
			(start -0.7874 -0.4064)
			(end 0.7874 -0.4064)
			(stroke
				(width 0.1524)
				(type default)
			)
			(layer "F.SilkS")
		)
		(fp_line
			(start 0.7874 0.4064)
			(end -0.7874 0.4064)
			(stroke
				(width 0.1524)
				(type default)
			)
			(layer "F.SilkS")
		)
		(fp_line
			(start -0.7874 0.4064)
			(end -0.7874 -0.4064)
			(stroke
				(width 0.1524)
				(type default)
			)
			(layer "F.SilkS")
		)
		(fp_line
			(start -0.12065 -0.305054)
			(end -0.12065 -0.2794)
			(stroke
				(width 0.1)
				(type default)
			)
			(layer "F.Fab")
		)
		(fp_line
			(start -0.67945 -0.305054)
			(end -0.12065 -0.305054)
			(stroke
				(width 0.1)
				(type default)
			)
			(layer "F.Fab")
		)
		(fp_line
			(start 0.67945 -0.3048)
			(end 0.67945 0.3048)
			(stroke
				(width 0.1)
				(type default)
			)
			(layer "F.Fab")
		)
		(fp_line
			(start 0.12065 -0.3048)
			(end 0.67945 -0.3048)
			(stroke
				(width 0.1)
				(type default)
			)
			(layer "F.Fab")
		)
		(fp_line
			(start 0.12065 -0.2794)
			(end 0.12065 -0.3048)
			(stroke
				(width 0.1)
				(type default)
			)
			(layer "F.Fab")
		)
		(fp_line
			(start -0.12065 -0.2794)
			(end 0.12065 -0.2794)
			(stroke
				(width 0.1)
				(type default)
			)
			(layer "F.Fab")
		)
		(fp_line
			(start 0.120396 0.2794)
			(end -0.12065 0.2794)
			(stroke
				(width 0.1)
				(type default)
			)
			(layer "F.Fab")
		)
		(fp_line
			(start -0.12065 0.2794)
			(end -0.12065 0.3048)
			(stroke
				(width 0.1)
				(type default)
			)
			(layer "F.Fab")
		)
		(fp_line
			(start 0.67945 0.3048)
			(end 0.120396 0.3048)
			(stroke
				(width 0.1)
				(type default)
			)
			(layer "F.Fab")
		)
		(fp_line
			(start 0.120396 0.3048)
			(end 0.120396 0.2794)
			(stroke
				(width 0.1)
				(type default)
			)
			(layer "F.Fab")
		)
		(fp_line
			(start -0.12065 0.3048)
			(end -0.67945 0.3048)
			(stroke
				(width 0.1)
				(type default)
			)
			(layer "F.Fab")
		)
		(fp_line
			(start -0.67945 0.3048)
			(end -0.67945 -0.305054)
			(stroke
				(width 0.1)
				(type default)
			)
			(layer "F.Fab")
		)
		(pad "1" smd circle
			(at -0.40005 0 90)
			(size 0 0)
			(layers "F.Cu" "F.Mask" "F.Paste")
			(net "PVCCFA_EHV_FIVRA_CPU0")
		)
		(pad "2" smd circle
			(at 0.40005 0 90)
			(size 0 0)
			(layers "F.Cu" "F.Mask" "F.Paste")
			(net "GND")
		)
	)
	(footprint ""
		(layer "F.Cu")
		(at 51.593496 -110.93577)
		(property "Reference" "R3725"
			(at 0 0 0)
			(layer "F.SilkS")
			(hide yes)
			(effects
				(font
					(size 1.27 1.27)
				)
			)
		)
		(property "Value" ""
			(at 0 0 0)
			(layer "F.Fab")
			(effects
				(font
					(size 1.27 1.27)
				)
			)
		)
		(duplicate_pad_numbers_are_jumpers no)
		(fp_line
			(start -0.7874 -0.4064)
			(end 0.7874 -0.4064)
			(stroke
				(width 0.1524)
				(type default)
			)
			(layer "F.SilkS")
		)
		(fp_line
			(start -0.7874 0.4064)
			(end -0.7874 -0.4064)
			(stroke
				(width 0.1524)
				(type default)
			)
			(layer "F.SilkS")
		)
		(fp_line
			(start 0.7874 -0.4064)
			(end 0.7874 0.4064)
			(stroke
				(width 0.1524)
				(type default)
			)
			(layer "F.SilkS")
		)
		(fp_line
			(start 0.7874 0.4064)
			(end -0.7874 0.4064)
			(stroke
				(width 0.1524)
				(type default)
			)
			(layer "F.SilkS")
		)
		(fp_line
			(start -0.67945 -0.305054)
			(end -0.12065 -0.305054)
			(stroke
				(width 0.1)
				(type default)
			)
			(layer "F.Fab")
		)
		(fp_line
			(start -0.67945 0.3048)
			(end -0.67945 -0.305054)
			(stroke
				(width 0.1)
				(type default)
			)
			(layer "F.Fab")
		)
		(fp_line
			(start -0.12065 -0.305054)
			(end -0.12065 -0.2794)
			(stroke
				(width 0.1)
				(type default)
			)
			(layer "F.Fab")
		)
		(fp_line
			(start -0.12065 -0.2794)
			(end 0.12065 -0.2794)
			(stroke
				(width 0.1)
				(type default)
			)
			(layer "F.Fab")
		)
		(fp_line
			(start -0.12065 0.2794)
			(end -0.12065 0.3048)
			(stroke
				(width 0.1)
				(type default)
			)
			(layer "F.Fab")
		)
		(fp_line
			(start -0.12065 0.3048)
			(end -0.67945 0.3048)
			(stroke
				(width 0.1)
				(type default)
			)
			(layer "F.Fab")
		)
		(fp_line
			(start 0.120396 0.2794)
			(end -0.12065 0.2794)
			(stroke
				(width 0.1)
				(type default)
			)
			(layer "F.Fab")
		)
		(fp_line
			(start 0.120396 0.3048)
			(end 0.120396 0.2794)
			(stroke
				(width 0.1)
				(type default)
			)
			(layer "F.Fab")
		)
		(fp_line
			(start 0.12065 -0.3048)
			(end 0.67945 -0.3048)
			(stroke
				(width 0.1)
				(type default)
			)
			(layer "F.Fab")
		)
		(fp_line
			(start 0.12065 -0.2794)
			(end 0.12065 -0.3048)
			(stroke
				(width 0.1)
				(type default)
			)
			(layer "F.Fab")
		)
		(fp_line
			(start 0.67945 -0.3048)
			(end 0.67945 0.3048)
			(stroke
				(width 0.1)
				(type default)
			)
			(layer "F.Fab")
		)
		(fp_line
			(start 0.67945 0.3048)
			(end 0.120396 0.3048)
			(stroke
				(width 0.1)
				(type default)
			)
			(layer "F.Fab")
		)
		(pad "1" smd circle
			(at -0.40005 0)
			(size 0 0)
			(layers "F.Cu" "F.Mask" "F.Paste")
			(net "P3V3_AUX")
		)
		(pad "2" smd circle
			(at 0.40005 0)
			(size 0 0)
			(layers "F.Cu" "F.Mask" "F.Paste")
			(net "SMB_LM75_0_3V3AUX_SCL")
		)
	)
	(footprint ""
		(layer "F.Cu")
		(at 145.131536 -64.701928)
		(property "Reference" "U145"
			(at -1.47066 2.016252 0)
			(unlocked yes)
			(layer "F.SilkS")
			(effects
				(font
					(size 0.7874 0.5842)
					(thickness 0.1524)
				)
				(justify left)
			)
		)
		(property "Value" ""
			(at 0 0 0)
			(layer "F.Fab")
			(effects
				(font
					(size 1.27 1.27)
				)
			)
		)
		(duplicate_pad_numbers_are_jumpers no)
		(fp_line
			(start -1.400048 1.100074)
			(end -1.400048 -1.100074)
			(stroke
				(width 0.1524)
				(type default)
			)
			(layer "F.SilkS")
		)
		(fp_line
			(start 1.400048 -1.100074)
			(end -1.400048 -1.100074)
			(stroke
				(width 0.1524)
				(type default)
			)
			(layer "F.SilkS")
		)
		(fp_line
			(start 1.400048 -1.100074)
			(end 1.400048 1.100074)
			(stroke
				(width 0.1524)
				(type default)
			)
			(layer "F.SilkS")
		)
		(fp_line
			(start 1.400048 1.100074)
			(end -1.400048 1.100074)
			(stroke
				(width 0.1524)
				(type default)
			)
			(layer "F.SilkS")
		)
		(fp_poly
			(pts
				(xy -1.05283 -1.437132) (xy -1.56083 -2.453132) (xy -0.54483 -2.453132)
			)
			(stroke
				(width 0)
				(type default)
			)
			(fill yes)
			(layer "F.SilkS")
		)
		(fp_line
			(start -0.674878 -1.100074)
			(end 0.674878 -1.100074)
			(stroke
				(width 0.1)
				(type default)
			)
			(layer "F.Fab")
		)
		(fp_line
			(start -0.674878 1.100074)
			(end -0.674878 -1.100074)
			(stroke
				(width 0.1)
				(type default)
			)
			(layer "F.Fab")
		)
		(fp_line
			(start 0.674878 -1.100074)
			(end 0.674878 1.100074)
			(stroke
				(width 0.1)
				(type default)
			)
			(layer "F.Fab")
		)
		(fp_line
			(start 0.674878 1.100074)
			(end -0.674878 1.100074)
			(stroke
				(width 0.1)
				(type default)
			)
			(layer "F.Fab")
		)
		(fp_poly
			(pts
				(xy -1.590548 -0.649986) (xy -2.606548 -1.157986) (xy -2.606548 -0.141986)
			)
			(stroke
				(width 0)
				(type default)
			)
			(fill yes)
			(layer "F.Fab")
		)
		(pad "1" smd rect
			(at -0.94996 -0.649986 270)
			(size 0.4318 0.6096)
			(layers "F.Cu" "F.Mask" "F.Paste")
			(net "FM_PS_EN_PLD_BUF1_R1")
		)
		(pad "2" smd rect
			(at -0.94996 0 270)
			(size 0.4318 0.6096)
			(layers "F.Cu" "F.Mask" "F.Paste")
			(net "E1S_0_PRSNT")
		)
		(pad "3" smd rect
			(at -0.94996 0.649986 270)
			(size 0.4318 0.6096)
			(layers "F.Cu" "F.Mask" "F.Paste")
			(net "GND")
		)
		(pad "4" smd rect
			(at 0.94996 0.649986 270)
			(size 0.4318 0.6096)
			(layers "F.Cu" "F.Mask" "F.Paste")
			(net "E1S_0_EN")
		)
		(pad "5" smd rect
			(at 0.94996 -0.649986 270)
			(size 0.4318 0.6096)
			(layers "F.Cu" "F.Mask" "F.Paste")
			(net "P3V3_AUX")
		)
	)
	(footprint ""
		(layer "F.Cu")
		(at 58.67273 -17.623536 90)
		(property "Reference" "C837"
			(at 0 0 90)
			(layer "F.SilkS")
			(hide yes)
			(effects
				(font
					(size 1.27 1.27)
				)
			)
		)
		(property "Value" ""
			(at 0 0 90)
			(layer "F.Fab")
			(effects
				(font
					(size 1.27 1.27)
				)
			)
		)
		(duplicate_pad_numbers_are_jumpers no)
		(fp_line
			(start 0.299974 -0.150114)
			(end 0.299974 0.150114)
			(stroke
				(width 0.1)
				(type default)
			)
			(layer "F.Fab")
		)
		(fp_line
			(start -0.299974 -0.150114)
			(end 0.299974 -0.150114)
			(stroke
				(width 0.1)
				(type default)
			)
			(layer "F.Fab")
		)
		(fp_line
			(start 0.299974 0.150114)
			(end -0.299974 0.150114)
			(stroke
				(width 0.1)
				(type default)
			)
			(layer "F.Fab")
		)
		(fp_line
			(start -0.299974 0.150114)
			(end -0.299974 -0.150114)
			(stroke
				(width 0.1)
				(type default)
			)
			(layer "F.Fab")
		)
		(pad "1" smd rect
			(at -0.2667 0 90)
			(size 0.3048 0.381)
			(layers "F.Cu" "F.Mask" "F.Paste")
			(net "P5E_CPU1_PE1_TX_C_DP<0>")
		)
		(pad "2" smd rect
			(at 0.2667 0 90)
			(size 0.3048 0.381)
			(layers "F.Cu" "F.Mask" "F.Paste")
			(net "P5E_CPU1_PE1_TX_DP<0>")
		)
	)
	(footprint ""
		(layer "F.Cu")
		(at 208.49336 -118.074948 180)
		(property "Reference" "R4170"
			(at 0 0 180)
			(layer "F.SilkS")
			(hide yes)
			(effects
				(font
					(size 1.27 1.27)
				)
			)
		)
		(property "Value" ""
			(at 0 0 180)
			(layer "F.Fab")
			(effects
				(font
					(size 1.27 1.27)
				)
			)
		)
		(duplicate_pad_numbers_are_jumpers no)
		(fp_line
			(start 0.7874 0.4064)
			(end -0.7874 0.4064)
			(stroke
				(width 0.1524)
				(type default)
			)
			(layer "F.SilkS")
		)
		(fp_line
			(start 0.7874 -0.4064)
			(end 0.7874 0.4064)
			(stroke
				(width 0.1524)
				(type default)
			)
			(layer "F.SilkS")
		)
		(fp_line
			(start -0.7874 0.4064)
			(end -0.7874 -0.4064)
			(stroke
				(width 0.1524)
				(type default)
			)
			(layer "F.SilkS")
		)
		(fp_line
			(start -0.7874 -0.4064)
			(end 0.7874 -0.4064)
			(stroke
				(width 0.1524)
				(type default)
			)
			(layer "F.SilkS")
		)
		(fp_line
			(start 0.67945 0.3048)
			(end 0.120396 0.3048)
			(stroke
				(width 0.1)
				(type default)
			)
			(layer "F.Fab")
		)
		(fp_line
			(start 0.67945 -0.3048)
			(end 0.67945 0.3048)
			(stroke
				(width 0.1)
				(type default)
			)
			(layer "F.Fab")
		)
		(fp_line
			(start 0.12065 -0.2794)
			(end 0.12065 -0.3048)
			(stroke
				(width 0.1)
				(type default)
			)
			(layer "F.Fab")
		)
		(fp_line
			(start 0.12065 -0.3048)
			(end 0.67945 -0.3048)
			(stroke
				(width 0.1)
				(type default)
			)
			(layer "F.Fab")
		)
		(fp_line
			(start 0.120396 0.3048)
			(end 0.120396 0.2794)
			(stroke
				(width 0.1)
				(type default)
			)
			(layer "F.Fab")
		)
		(fp_line
			(start 0.120396 0.2794)
			(end -0.12065 0.2794)
			(stroke
				(width 0.1)
				(type default)
			)
			(layer "F.Fab")
		)
		(fp_line
			(start -0.12065 0.3048)
			(end -0.67945 0.3048)
			(stroke
				(width 0.1)
				(type default)
			)
			(layer "F.Fab")
		)
		(fp_line
			(start -0.12065 0.2794)
			(end -0.12065 0.3048)
			(stroke
				(width 0.1)
				(type default)
			)
			(layer "F.Fab")
		)
		(fp_line
			(start -0.12065 -0.2794)
			(end 0.12065 -0.2794)
			(stroke
				(width 0.1)
				(type default)
			)
			(layer "F.Fab")
		)
		(fp_line
			(start -0.12065 -0.305054)
			(end -0.12065 -0.2794)
			(stroke
				(width 0.1)
				(type default)
			)
			(layer "F.Fab")
		)
		(fp_line
			(start -0.67945 0.3048)
			(end -0.67945 -0.305054)
			(stroke
				(width 0.1)
				(type default)
			)
			(layer "F.Fab")
		)
		(fp_line
			(start -0.67945 -0.305054)
			(end -0.12065 -0.305054)
			(stroke
				(width 0.1)
				(type default)
			)
			(layer "F.Fab")
		)
		(pad "1" smd circle
			(at -0.40005 0 180)
			(size 0 0)
			(layers "F.Cu" "F.Mask" "F.Paste")
			(net "GPU_3V3IO_RSVD1_ISO")
		)
		(pad "2" smd circle
			(at 0.40005 0 180)
			(size 0 0)
			(layers "F.Cu" "F.Mask" "F.Paste")
			(net "GPU_3V3IO_RSVD1_ISO_R")
		)
	)
	(footprint ""
		(layer "F.Cu")
		(at 32.761428 -98.570034 180)
		(property "Reference" "C2175"
			(at 0 0 180)
			(layer "F.SilkS")
			(hide yes)
			(effects
				(font
					(size 1.27 1.27)
				)
			)
		)
		(property "Value" ""
			(at 0 0 180)
			(layer "F.Fab")
			(effects
				(font
					(size 1.27 1.27)
				)
			)
		)
		(duplicate_pad_numbers_are_jumpers no)
		(fp_line
			(start 0.7874 0.4064)
			(end -0.7874 0.4064)
			(stroke
				(width 0.1524)
				(type default)
			)
			(layer "F.SilkS")
		)
		(fp_line
			(start 0.7874 -0.4064)
			(end 0.7874 0.4064)
			(stroke
				(width 0.1524)
				(type default)
			)
			(layer "F.SilkS")
		)
		(fp_line
			(start -0.7874 0.4064)
			(end -0.7874 -0.4064)
			(stroke
				(width 0.1524)
				(type default)
			)
			(layer "F.SilkS")
		)
		(fp_line
			(start -0.7874 -0.4064)
			(end 0.7874 -0.4064)
			(stroke
				(width 0.1524)
				(type default)
			)
			(layer "F.SilkS")
		)
		(fp_line
			(start 0.67945 0.3048)
			(end 0.120396 0.3048)
			(stroke
				(width 0.1)
				(type default)
			)
			(layer "F.Fab")
		)
		(fp_line
			(start 0.67945 -0.3048)
			(end 0.67945 0.3048)
			(stroke
				(width 0.1)
				(type default)
			)
			(layer "F.Fab")
		)
		(fp_line
			(start 0.12065 -0.2794)
			(end 0.12065 -0.3048)
			(stroke
				(width 0.1)
				(type default)
			)
			(layer "F.Fab")
		)
		(fp_line
			(start 0.12065 -0.3048)
			(end 0.67945 -0.3048)
			(stroke
				(width 0.1)
				(type default)
			)
			(layer "F.Fab")
		)
		(fp_line
			(start 0.120396 0.3048)
			(end 0.120396 0.2794)
			(stroke
				(width 0.1)
				(type default)
			)
			(layer "F.Fab")
		)
		(fp_line
			(start 0.120396 0.2794)
			(end -0.12065 0.2794)
			(stroke
				(width 0.1)
				(type default)
			)
			(layer "F.Fab")
		)
		(fp_line
			(start -0.12065 0.3048)
			(end -0.67945 0.3048)
			(stroke
				(width 0.1)
				(type default)
			)
			(layer "F.Fab")
		)
		(fp_line
			(start -0.12065 0.2794)
			(end -0.12065 0.3048)
			(stroke
				(width 0.1)
				(type default)
			)
			(layer "F.Fab")
		)
		(fp_line
			(start -0.12065 -0.2794)
			(end 0.12065 -0.2794)
			(stroke
				(width 0.1)
				(type default)
			)
			(layer "F.Fab")
		)
		(fp_line
			(start -0.12065 -0.305054)
			(end -0.12065 -0.2794)
			(stroke
				(width 0.1)
				(type default)
			)
			(layer "F.Fab")
		)
		(fp_line
			(start -0.67945 0.3048)
			(end -0.67945 -0.305054)
			(stroke
				(width 0.1)
				(type default)
			)
			(layer "F.Fab")
		)
		(fp_line
			(start -0.67945 -0.305054)
			(end -0.12065 -0.305054)
			(stroke
				(width 0.1)
				(type default)
			)
			(layer "F.Fab")
		)
		(pad "1" smd circle
			(at -0.40005 0 180)
			(size 0 0)
			(layers "F.Cu" "F.Mask" "F.Paste")
			(net "P12V_OCP_V3_2_ISENSE_MAM")
		)
		(pad "2" smd circle
			(at 0.40005 0 180)
			(size 0 0)
			(layers "F.Cu" "F.Mask" "F.Paste")
			(net "GND")
		)
	)
)
